(kicad_pcb
	(version 20260206)
	(generator "pcbnew")
	(generator_version "10.0")
	(general
		(thickness 1.6)
		(legacy_teardrops no)
	)
	(paper "A4")
	(title_block
		(title "v1-tray-backplane — T6M_tray_BP_c_1023_1120.brd")
		(comment 1 "Open CloudServer (Microsoft) / footprints 16-19 of 170")
	)
	(layers
		(0 "F.Cu" signal "TOP")
		(4 "In1.Cu" signal "GND")
		(6 "In2.Cu" signal "IN1")
		(8 "In3.Cu" signal "VCC")
		(10 "In4.Cu" signal "VCC1")
		(12 "In5.Cu" signal "IN2")
		(14 "In6.Cu" signal "GND1")
		(2 "B.Cu" signal "BOTTOM")
		(9 "F.Adhes" user "F.Adhesive")
		(11 "B.Adhes" user "B.Adhesive")
		(13 "F.Paste" user "Package Geometry/Pastemask Top")
		(15 "B.Paste" user "Package Geometry/Pastemask Bottom")
		(5 "F.SilkS" user "Ref Des/Silkscreen Top")
		(7 "B.SilkS" user "Ref Des/Silkscreen Bottom")
		(1 "F.Mask" user "Board Geometry/Soldermask Top")
		(3 "B.Mask" user "Board Geometry/Soldermask Bottom")
		(17 "Dwgs.User" user "User.Drawings")
		(19 "Cmts.User" user "User.Comments")
		(21 "Eco1.User" user "User.Eco1")
		(23 "Eco2.User" user "User.Eco2")
		(25 "Edge.Cuts" user "Board Geometry/Outline")
		(27 "Margin" user)
		(31 "F.CrtYd" user "Package Geometry/Place Bound Top")
		(29 "B.CrtYd" user "Package Geometry/Place Bound Bottom")
		(35 "F.Fab" user "Ref Des/Assembly Top")
		(33 "B.Fab" user "Ref Des/Assembly Bottom")
	)
	(footprint ""
		(layer "F.Cu")
		(at 90.9828 -30.897068)
		(property "Reference" "R78"
			(at -7.0866 1.70307 0)
			(unlocked yes)
			(layer "F.SilkS")
			(effects
				(font
					(size 0.7874 0.5842)
					(thickness 0.1524)
				)
				(justify left)
			)
		)
		(property "Value" ""
			(at 0 0 0)
			(layer "F.Fab")
			(effects
				(font
					(size 1.27 1.27)
				)
			)
		)
		(duplicate_pad_numbers_are_jumpers no)
		(fp_line
			(start -1.905 -0.8636)
			(end 1.905 -0.8636)
			(stroke
				(width 0.1524)
				(type default)
			)
			(layer "F.SilkS")
		)
		(fp_line
			(start -1.905 0.8636)
			(end -1.905 -0.8636)
			(stroke
				(width 0.1524)
				(type default)
			)
			(layer "F.SilkS")
		)
		(fp_line
			(start 1.905 -0.8636)
			(end 1.905 0.8636)
			(stroke
				(width 0.1524)
				(type default)
			)
			(layer "F.SilkS")
		)
		(fp_line
			(start 1.905 0.8636)
			(end -1.905 0.8636)
			(stroke
				(width 0.1524)
				(type default)
			)
			(layer "F.SilkS")
		)
		(fp_poly
			(pts
				(xy 1.524 0.6858) (xy 1.524 -0.6858) (xy 1.524 -0.7366) (xy -1.524 -0.7366) (xy -1.524 -0.6858)
				(xy -1.524 0.6858) (xy -1.524 0.7366) (xy 1.524 0.7366)
			)
			(stroke
				(width 0)
				(type default)
			)
			(fill no)
			(layer "F.CrtYd")
		)
		(pad "1" smd rect
			(at 0.94996 0)
			(size 1.1176 1.3716)
			(layers "F.Cu" "F.Mask" "F.Paste")
			(net "P3V3_BLAD1")
		)
		(pad "2" smd rect
			(at -0.94996 0)
			(size 1.1176 1.3716)
			(layers "F.Cu" "F.Mask" "F.Paste")
			(net "P3V3_10G_2_VCCT")
		)
	)
	(footprint ""
		(layer "F.Cu")
		(at 22.809962 -27.500072 180)
		(property "Reference" "J21"
			(at -2.81559 -9.110218 90)
			(unlocked yes)
			(layer "F.SilkS")
			(effects
				(font
					(size 0.7874 0.5842)
					(thickness 0.1524)
				)
				(justify left)
			)
		)
		(property "Value" ""
			(at 0 0 180)
			(layer "F.Fab")
			(effects
				(font
					(size 1.27 1.27)
				)
			)
		)
		(duplicate_pad_numbers_are_jumpers no)
		(fp_line
			(start 4.150106 2.325116)
			(end -2.15011 2.325116)
			(stroke
				(width 0.1524)
				(type default)
			)
			(layer "F.SilkS")
		)
		(fp_line
			(start 4.150106 -12.325096)
			(end 4.150106 2.325116)
			(stroke
				(width 0.1524)
				(type default)
			)
			(layer "F.SilkS")
		)
		(fp_line
			(start -1.500124 -3.800094)
			(end -2.15011 -3.800094)
			(stroke
				(width 0.1524)
				(type default)
			)
			(layer "F.SilkS")
		)
		(fp_line
			(start -1.500124 -6.199886)
			(end -1.500124 -3.800094)
			(stroke
				(width 0.1524)
				(type default)
			)
			(layer "F.SilkS")
		)
		(fp_line
			(start -2.15011 2.325116)
			(end -2.15011 -12.325096)
			(stroke
				(width 0.1524)
				(type default)
			)
			(layer "F.SilkS")
		)
		(fp_line
			(start -2.15011 -6.199886)
			(end -1.500124 -6.199886)
			(stroke
				(width 0.1524)
				(type default)
			)
			(layer "F.SilkS")
		)
		(fp_line
			(start -2.15011 -12.325096)
			(end 4.150106 -12.325096)
			(stroke
				(width 0.1524)
				(type default)
			)
			(layer "F.SilkS")
		)
		(fp_poly
			(pts
				(xy -1.143 -12.69238) (xy -0.381 -14.21638) (xy -1.905 -14.21638)
			)
			(stroke
				(width 0)
				(type default)
			)
			(fill yes)
			(layer "F.SilkS")
		)
		(fp_poly
			(pts
				(xy 2.752598 -10.74039) (xy -0.727202 -10.74039) (xy -0.752602 -10.74039) (xy -0.752602 0.74041)
				(xy 2.752598 0.74041)
			)
			(stroke
				(width 0)
				(type default)
			)
			(fill no)
			(layer "B.CrtYd")
		)
		(fp_poly
			(pts
				(xy -2.15011 -12.325096) (xy -2.15011 2.325116) (xy 4.150106 2.325116) (xy 4.150106 -12.325096)
			)
			(stroke
				(width 0)
				(type default)
			)
			(fill no)
			(layer "F.CrtYd")
		)
		(fp_line
			(start 4.150106 2.325116)
			(end -2.15011 2.325116)
			(stroke
				(width 0.1)
				(type default)
			)
			(layer "F.Fab")
		)
		(fp_line
			(start 4.150106 -12.325096)
			(end 4.150106 2.325116)
			(stroke
				(width 0.1)
				(type default)
			)
			(layer "F.Fab")
		)
		(fp_line
			(start -2.15011 2.325116)
			(end -2.15011 -12.325096)
			(stroke
				(width 0.1)
				(type default)
			)
			(layer "F.Fab")
		)
		(fp_line
			(start -2.15011 -12.325096)
			(end 4.150106 -12.325096)
			(stroke
				(width 0.1)
				(type default)
			)
			(layer "F.Fab")
		)
		(fp_poly
			(pts
				(xy -2.350516 -9.992614) (xy -3.874516 -10.754614) (xy -3.874516 -9.230614)
			)
			(stroke
				(width 0)
				(type default)
			)
			(fill yes)
			(layer "F.Fab")
		)
		(fp_text user "2"
			(at 5.029454 -9.962896 0)
			(unlocked yes)
			(layer "F.SilkS")
			(effects
				(font
					(size 0.7874 0.5842)
					(thickness 0.1524)
				)
				(justify left)
			)
		)
		(fp_text user "12"
			(at 2.631186 3.270504 0)
			(unlocked yes)
			(layer "F.SilkS")
			(effects
				(font
					(size 0.7874 0.5842)
					(thickness 0.1524)
				)
				(justify left)
			)
		)
		(fp_text user "11"
			(at -0.543814 3.188208 0)
			(unlocked yes)
			(layer "F.SilkS")
			(effects
				(font
					(size 0.7874 0.5842)
					(thickness 0.1524)
				)
				(justify left)
			)
		)
		(fp_text user "1"
			(at -1.599946 -13.080492 0)
			(unlocked yes)
			(layer "F.SilkS")
			(effects
				(font
					(size 0.7874 0.5842)
					(thickness 0.1524)
				)
				(justify left)
			)
		)
		(fp_text user "2"
			(at 2.053844 -10.992104 90)
			(unlocked yes)
			(layer "B.SilkS")
			(effects
				(font
					(size 0.7874 0.5842)
					(thickness 0.1524)
				)
				(justify left mirror)
			)
		)
		(fp_text user "12"
			(at 2.015744 2.274824 90)
			(unlocked yes)
			(layer "B.SilkS")
			(effects
				(font
					(size 0.7874 0.5842)
					(thickness 0.1524)
				)
				(justify left mirror)
			)
		)
		(fp_text user "1"
			(at 0.015748 -10.928604 90)
			(unlocked yes)
			(layer "B.SilkS")
			(effects
				(font
					(size 0.7874 0.5842)
					(thickness 0.1524)
				)
				(justify left mirror)
			)
		)
		(fp_text user "11"
			(at -0.098552 2.058924 90)
			(unlocked yes)
			(layer "B.SilkS")
			(effects
				(font
					(size 0.7874 0.5842)
					(thickness 0.1524)
				)
				(justify left mirror)
			)
		)
		(fp_text user "2"
			(at 2.079244 -10.661904 90)
			(unlocked yes)
			(layer "B.Fab")
			(effects
				(font
					(size 0.7874 0.5842)
					(thickness 0.000001)
				)
				(justify left mirror)
			)
		)
		(fp_text user "12"
			(at 2.066544 2.071624 90)
			(unlocked yes)
			(layer "B.Fab")
			(effects
				(font
					(size 0.7874 0.5842)
					(thickness 0.000001)
				)
				(justify left mirror)
			)
		)
		(fp_text user "1"
			(at 0.041148 -10.598404 90)
			(unlocked yes)
			(layer "B.Fab")
			(effects
				(font
					(size 0.7874 0.5842)
					(thickness 0.000001)
				)
				(justify left mirror)
			)
		)
		(fp_text user "11"
			(at -0.047752 1.855724 90)
			(unlocked yes)
			(layer "B.Fab")
			(effects
				(font
					(size 0.7874 0.5842)
					(thickness 0.000001)
				)
				(justify left mirror)
			)
		)
		(fp_text user "12"
			(at 4.733544 0.332994 90)
			(unlocked yes)
			(layer "F.Fab")
			(effects
				(font
					(size 0.7874 0.5842)
					(thickness 0.000001)
				)
				(justify left)
			)
		)
		(fp_text user "2"
			(at 4.708144 -11.031474 90)
			(unlocked yes)
			(layer "F.Fab")
			(effects
				(font
					(size 0.7874 0.5842)
					(thickness 0.000001)
				)
				(justify left)
			)
		)
		(fp_text user "1"
			(at -2.727452 -10.879074 90)
			(unlocked yes)
			(layer "F.Fab")
			(effects
				(font
					(size 0.7874 0.5842)
					(thickness 0.000001)
				)
				(justify left)
			)
		)
		(fp_text user "11"
			(at -2.740152 -0.632206 90)
			(unlocked yes)
			(layer "F.Fab")
			(effects
				(font
					(size 0.7874 0.5842)
					(thickness 0.000001)
				)
				(justify left)
			)
		)
		(pad "" np_thru_hole circle
			(at 0.999998 -8.999982 90)
			(size 1.0668 1.0668)
			(drill 1.0668)
			(layers "*.Cu" "*.Mask")
			(clearance 0.381)
			(thermal_gap 0.381)
		)
		(pad "" np_thru_hole circle
			(at 0.999998 -0.999998 90)
			(size 1.0668 1.0668)
			(drill 1.0668)
			(layers "*.Cu" "*.Mask")
			(clearance 0.381)
			(thermal_gap 0.381)
		)
		(pad "1" thru_hole circle
			(at 0 -9.99998 90)
			(size 1.3716 1.3716)
			(drill 0.9652)
			(layers "*.Cu" "*.Mask")
			(remove_unused_layers no)
			(net "PS_EN_PSU_N")
			(clearance 0.0508)
			(thermal_gap 0.0508)
		)
		(pad "2" thru_hole circle
			(at 1.999996 -9.99998 90)
			(size 1.3716 1.3716)
			(drill 0.9652)
			(layers "*.Cu" "*.Mask")
			(remove_unused_layers no)
			(net "Net_222")
			(clearance 0.0508)
			(thermal_gap 0.0508)
		)
		(pad "3" thru_hole circle
			(at 0 -7.999984 90)
			(size 1.3716 1.3716)
			(drill 0.9652)
			(layers "*.Cu" "*.Mask")
			(remove_unused_layers no)
			(net "Net_223")
			(clearance 0.0508)
			(thermal_gap 0.0508)
		)
		(pad "4" thru_hole circle
			(at 1.999996 -7.999984 90)
			(size 1.3716 1.3716)
			(drill 0.9652)
			(layers "*.Cu" "*.Mask")
			(remove_unused_layers no)
			(net "Net_224")
			(clearance 0.0508)
			(thermal_gap 0.0508)
		)
		(pad "5" thru_hole circle
			(at 0 -5.999988 90)
			(size 1.3716 1.3716)
			(drill 0.9652)
			(layers "*.Cu" "*.Mask")
			(remove_unused_layers no)
			(net "Net_225")
			(clearance 0.0508)
			(thermal_gap 0.0508)
		)
		(pad "6" thru_hole circle
			(at 1.999996 -5.999988 90)
			(size 1.3716 1.3716)
			(drill 0.9652)
			(layers "*.Cu" "*.Mask")
			(remove_unused_layers no)
			(net "Net_226")
			(clearance 0.0508)
			(thermal_gap 0.0508)
		)
		(pad "7" thru_hole circle
			(at 0 -3.999992 90)
			(size 1.3716 1.3716)
			(drill 0.9652)
			(layers "*.Cu" "*.Mask")
			(remove_unused_layers no)
			(net "Net_227")
			(clearance 0.0508)
			(thermal_gap 0.0508)
		)
		(pad "8" thru_hole circle
			(at 1.999996 -3.999992 90)
			(size 1.3716 1.3716)
			(drill 0.9652)
			(layers "*.Cu" "*.Mask")
			(remove_unused_layers no)
			(net "Net_228")
			(clearance 0.0508)
			(thermal_gap 0.0508)
		)
		(pad "9" thru_hole circle
			(at 0 -1.999996 90)
			(size 1.3716 1.3716)
			(drill 0.9652)
			(layers "*.Cu" "*.Mask")
			(remove_unused_layers no)
			(net "Net_229")
			(clearance 0.0508)
			(thermal_gap 0.0508)
		)
		(pad "10" thru_hole circle
			(at 1.999996 -1.999996 90)
			(size 1.3716 1.3716)
			(drill 0.9652)
			(layers "*.Cu" "*.Mask")
			(remove_unused_layers no)
			(net "Net_220")
			(clearance 0.0508)
			(thermal_gap 0.0508)
		)
		(pad "11" thru_hole circle
			(at 0 0 90)
			(size 1.3716 1.3716)
			(drill 0.9652)
			(layers "*.Cu" "*.Mask")
			(remove_unused_layers no)
			(net "GND")
			(clearance 0.0508)
			(thermal_gap 0.0508)
		)
		(pad "12" thru_hole circle
			(at 1.999996 0 90)
			(size 1.3716 1.3716)
			(drill 0.9652)
			(layers "*.Cu" "*.Mask")
			(remove_unused_layers no)
			(net "Net_221")
			(clearance 0.0508)
			(thermal_gap 0.0508)
		)
		(zone
			(layers "F.Cu" "B.Cu" "In1.Cu" "In2.Cu" "In3.Cu" "In4.Cu" "In5.Cu" "In6.Cu")
			(hatch none 0.5)
			(connect_pads
				(clearance 0)
			)
			(min_thickness 0.25)
			(keepout
				(tracks not_allowed)
				(vias allowed)
				(pads allowed)
				(copperpour not_allowed)
				(footprints allowed)
			)
			(placement
				(enabled no)
				(sheetname "")
			)
			(fill
				(thermal_gap 0.5)
				(thermal_bridge_width 0.5)
				(island_removal_mode 0)
			)
			(polygon
				(pts
					(arc
						(start 22.747732 -26.500074)
						(mid 22.737789 -26.363625)
						(end 22.708108 -26.230072)
					)
					(xy 22.063964 -26.230072) (xy 22.063964 -26.207466)
					(arc
						(start 22.063964 -25.597358)
						(mid 21.809964 -25.562304)
						(end 21.555964 -25.597358)
					)
					(xy 21.555964 -26.230072)
					(arc
						(start 20.91182 -26.230072)
						(mid 20.872114 -26.499551)
						(end 20.911566 -26.76906)
					)
					(xy 21.555456 -26.76906)
					(arc
						(start 21.555456 -27.402536)
						(mid 21.809964 -27.437737)
						(end 22.064472 -27.402536)
					)
					(xy 22.064472 -26.766266)
					(arc
						(start 22.709124 -26.766266)
						(mid 22.738005 -26.63456)
						(end 22.747732 -26.500074)
					)
				)
			)
		)
		(zone
			(layers "F.Cu" "B.Cu" "In1.Cu" "In2.Cu" "In3.Cu" "In4.Cu" "In5.Cu" "In6.Cu")
			(hatch none 0.5)
			(connect_pads
				(clearance 0)
			)
			(min_thickness 0.25)
			(keepout
				(tracks not_allowed)
				(vias allowed)
				(pads allowed)
				(copperpour not_allowed)
				(footprints allowed)
			)
			(placement
				(enabled no)
				(sheetname "")
			)
			(fill
				(thermal_gap 0.5)
				(thermal_bridge_width 0.5)
				(island_removal_mode 0)
			)
			(polygon
				(pts
					(arc
						(start 22.747732 -18.50009)
						(mid 22.737789 -18.363641)
						(end 22.708108 -18.230088)
					)
					(xy 22.063964 -18.230088) (xy 22.063964 -18.207482)
					(arc
						(start 22.063964 -17.597374)
						(mid 21.809964 -17.56232)
						(end 21.555964 -17.597374)
					)
					(xy 21.555964 -18.230088)
					(arc
						(start 20.91182 -18.230088)
						(mid 20.872114 -18.499567)
						(end 20.911566 -18.769076)
					)
					(xy 21.555456 -18.769076)
					(arc
						(start 21.555456 -19.402552)
						(mid 21.809964 -19.437753)
						(end 22.064472 -19.402552)
					)
					(xy 22.064472 -18.766282)
					(arc
						(start 22.709124 -18.766282)
						(mid 22.738005 -18.634576)
						(end 22.747732 -18.50009)
					)
				)
			)
		)
	)
	(footprint ""
		(layer "F.Cu")
		(at 344.333068 -21.674582 -90)
		(property "Reference" "R61"
			(at -3.336036 56.907684 90)
			(unlocked yes)
			(layer "F.SilkS")
			(effects
				(font
					(size 0.7874 0.5842)
					(thickness 0.1524)
				)
				(justify left)
			)
		)
		(property "Value" ""
			(at 0 0 270)
			(layer "F.Fab")
			(effects
				(font
					(size 1.27 1.27)
				)
			)
		)
		(duplicate_pad_numbers_are_jumpers no)
		(fp_line
			(start -0.7874 0.4064)
			(end -0.7874 -0.4064)
			(stroke
				(width 0.1524)
				(type default)
			)
			(layer "F.SilkS")
		)
		(fp_line
			(start 0.7874 0.4064)
			(end -0.7874 0.4064)
			(stroke
				(width 0.1524)
				(type default)
			)
			(layer "F.SilkS")
		)
		(fp_line
			(start -0.7874 -0.4064)
			(end 0.7874 -0.4064)
			(stroke
				(width 0.1524)
				(type default)
			)
			(layer "F.SilkS")
		)
		(fp_line
			(start 0.7874 -0.4064)
			(end 0.7874 0.4064)
			(stroke
				(width 0.1524)
				(type default)
			)
			(layer "F.SilkS")
		)
		(fp_poly
			(pts
				(xy -0.508 0.2794) (xy -0.508 0.2286) (xy -0.635 0.2286) (xy -0.635 -0.254) (xy -0.5334 -0.254)
				(xy -0.5334 -0.2794) (xy 0.5334 -0.2794) (xy 0.5334 -0.254) (xy 0.635 -0.254) (xy 0.635 0.254) (xy 0.5334 0.254)
				(xy 0.5334 0.2794)
			)
			(stroke
				(width 0)
				(type default)
			)
			(fill no)
			(layer "F.CrtYd")
		)
		(pad "1" smd rect
			(at 0.40005 0 270)
			(size 0.4572 0.508)
			(layers "F.Cu" "F.Mask" "F.Paste")
			(net "SKU_PIN_BLAD2_2")
		)
		(pad "2" smd rect
			(at -0.40005 0 270)
			(size 0.4572 0.508)
			(layers "F.Cu" "F.Mask" "F.Paste")
			(net "P3V3_BLAD2")
		)
	)
	(footprint ""
		(layer "F.Cu")
		(at 209.810096 -41.500044 180)
		(property "Reference" "H4"
			(at -3.594608 -3.83794 0)
			(unlocked yes)
			(layer "F.SilkS")
			(effects
				(font
					(size 0.7874 0.5842)
					(thickness 0.1524)
				)
				(justify left)
			)
		)
		(property "Value" ""
			(at 0 0 180)
			(layer "F.Fab")
			(effects
				(font
					(size 1.27 1.27)
				)
			)
		)
		(duplicate_pad_numbers_are_jumpers no)
		(fp_poly
			(pts
				(arc
					(start 3.999992 5.999988)
					(mid 0 9.99998)
					(end -3.999992 5.999988)
				)
				(arc
					(start -3.999992 0)
					(mid 0 -3.999992)
					(end 3.999992 0)
				)
			)
			(stroke
				(width 0)
				(type default)
			)
			(fill no)
			(layer "B.CrtYd")
		)
		(fp_poly
			(pts
				(arc
					(start 3.999992 5.999988)
					(mid 0 9.99998)
					(end -3.999992 5.999988)
				)
				(arc
					(start -3.999992 0)
					(mid 0 -3.999992)
					(end 3.999992 0)
				)
			)
			(stroke
				(width 0)
				(type default)
			)
			(fill no)
			(layer "F.CrtYd")
		)
		(pad "" np_thru_hole circle
			(at 0 0 180)
			(size 3.5052 3.5052)
			(drill 3.5052)
			(layers "*.Cu" "*.Mask")
			(clearance 0.381)
			(thermal_gap 0.381)
		)
		(zone
			(layers "F.Cu" "B.Cu" "In1.Cu" "In2.Cu" "In3.Cu" "In4.Cu" "In5.Cu" "In6.Cu")
			(hatch none 0.5)
			(connect_pads
				(clearance 0)
			)
			(min_thickness 0.25)
			(keepout
				(tracks not_allowed)
				(vias allowed)
				(pads allowed)
				(copperpour not_allowed)
				(footprints allowed)
			)
			(placement
				(enabled no)
				(sheetname "")
			)
			(fill
				(thermal_gap 0.5)
				(thermal_bridge_width 0.5)
				(island_removal_mode 0)
			)
			(polygon
				(pts
					(arc
						(start 207.398366 -44.952666)
						(mid 209.810096 -51.007954)
						(end 212.221826 -44.952666)
					)
					(arc
						(start 212.221826 -44.952666)
						(mid 212.108197 -44.789805)
						(end 212.068156 -44.595288)
					)
					(arc
						(start 212.068156 -41.500044)
						(mid 209.810096 -39.241984)
						(end 207.552036 -41.500044)
					)
					(arc
						(start 207.552036 -44.595288)
						(mid 207.51205 -44.789828)
						(end 207.398366 -44.952666)
					)
				)
			)
		)
	)
)
